(kicad_pcb
	(version 20260206)
	(generator "pcbnew")
	(generator_version "10.0")
	(general
		(thickness 1.6)
		(legacy_teardrops no)
	)
	(paper "A4")
	(title_block
		(title "03242023_DA0F0TMBIJ0_F0T_Motherboard_J_brd_V01_OCP.brd")
		(comment 1 "Grand Teton / footprints 4878-4883 of 6105")
	)
	(layers
		(0 "F.Cu" signal "TOP")
		(4 "In1.Cu" signal "GND")
		(6 "In2.Cu" signal "IN1")
		(8 "In3.Cu" signal "GND1")
		(10 "In4.Cu" signal "IN2")
		(12 "In5.Cu" signal "GND2")
		(14 "In6.Cu" signal "IN3")
		(16 "In7.Cu" signal "GND3")
		(18 "In8.Cu" signal "VCC")
		(20 "In9.Cu" signal "VCC1")
		(22 "In10.Cu" signal "GND4")
		(24 "In11.Cu" signal "IN4")
		(26 "In12.Cu" signal "GND5")
		(28 "In13.Cu" signal "IN5")
		(30 "In14.Cu" signal "GND6")
		(32 "In15.Cu" signal "IN6")
		(34 "In16.Cu" signal "GND7")
		(2 "B.Cu" signal "BOTTOM")
		(9 "F.Adhes" user "F.Adhesive")
		(11 "B.Adhes" user "B.Adhesive")
		(13 "F.Paste" user "Package Geometry/Pastemask Top")
		(15 "B.Paste" user "Package Geometry/Pastemask Bottom")
		(5 "F.SilkS" user "Ref Des/Silkscreen Top")
		(7 "B.SilkS" user "Ref Des/Silkscreen Bottom")
		(1 "F.Mask" user "Board Geometry/Soldermask Top")
		(3 "B.Mask" user "Board Geometry/Soldermask Bottom")
		(17 "Dwgs.User" user "User.Drawings")
		(19 "Cmts.User" user "User.Comments")
		(21 "Eco1.User" user "User.Eco1")
		(23 "Eco2.User" user "User.Eco2")
		(25 "Edge.Cuts" user "Board Geometry/Outline")
		(27 "Margin" user)
		(31 "F.CrtYd" user "Package Geometry/Place Bound Top")
		(29 "B.CrtYd" user "Package Geometry/Place Bound Bottom")
		(35 "F.Fab" user "Ref Des/Assembly Top")
		(33 "B.Fab" user "Ref Des/Assembly Bottom")
	)
	(footprint ""
		(layer "B.Cu")
		(at 290.301934 -319.068958 -90)
		(property "Reference" "R2728"
			(at 0 0 90)
			(layer "B.SilkS")
			(hide yes)
			(effects
				(font
					(size 1.27 1.27)
				)
				(justify mirror)
			)
		)
		(property "Value" ""
			(at 0 0 90)
			(layer "B.Fab")
			(effects
				(font
					(size 1.27 1.27)
				)
				(justify mirror)
			)
		)
		(duplicate_pad_numbers_are_jumpers no)
		(fp_line
			(start -0.7874 0.4064)
			(end 0.7874 0.4064)
			(stroke
				(width 0.1524)
				(type default)
			)
			(layer "B.SilkS")
		)
		(fp_line
			(start 0.7874 0.4064)
			(end 0.7874 -0.4064)
			(stroke
				(width 0.1524)
				(type default)
			)
			(layer "B.SilkS")
		)
		(fp_line
			(start -0.7874 -0.4064)
			(end -0.7874 0.4064)
			(stroke
				(width 0.1524)
				(type default)
			)
			(layer "B.SilkS")
		)
		(fp_line
			(start 0.7874 -0.4064)
			(end -0.7874 -0.4064)
			(stroke
				(width 0.1524)
				(type default)
			)
			(layer "B.SilkS")
		)
		(fp_line
			(start -0.67945 0.3048)
			(end -0.120396 0.3048)
			(stroke
				(width 0.1)
				(type default)
			)
			(layer "B.Fab")
		)
		(fp_line
			(start -0.120396 0.3048)
			(end -0.120396 0.2794)
			(stroke
				(width 0.1)
				(type default)
			)
			(layer "B.Fab")
		)
		(fp_line
			(start 0.12065 0.3048)
			(end 0.67945 0.3048)
			(stroke
				(width 0.1)
				(type default)
			)
			(layer "B.Fab")
		)
		(fp_line
			(start 0.67945 0.3048)
			(end 0.67945 -0.305054)
			(stroke
				(width 0.1)
				(type default)
			)
			(layer "B.Fab")
		)
		(fp_line
			(start -0.120396 0.2794)
			(end 0.12065 0.2794)
			(stroke
				(width 0.1)
				(type default)
			)
			(layer "B.Fab")
		)
		(fp_line
			(start 0.12065 0.2794)
			(end 0.12065 0.3048)
			(stroke
				(width 0.1)
				(type default)
			)
			(layer "B.Fab")
		)
		(fp_line
			(start -0.12065 -0.2794)
			(end -0.12065 -0.3048)
			(stroke
				(width 0.1)
				(type default)
			)
			(layer "B.Fab")
		)
		(fp_line
			(start 0.12065 -0.2794)
			(end -0.12065 -0.2794)
			(stroke
				(width 0.1)
				(type default)
			)
			(layer "B.Fab")
		)
		(fp_line
			(start -0.67945 -0.3048)
			(end -0.67945 0.3048)
			(stroke
				(width 0.1)
				(type default)
			)
			(layer "B.Fab")
		)
		(fp_line
			(start -0.12065 -0.3048)
			(end -0.67945 -0.3048)
			(stroke
				(width 0.1)
				(type default)
			)
			(layer "B.Fab")
		)
		(fp_line
			(start 0.12065 -0.305054)
			(end 0.12065 -0.2794)
			(stroke
				(width 0.1)
				(type default)
			)
			(layer "B.Fab")
		)
		(fp_line
			(start 0.67945 -0.305054)
			(end 0.12065 -0.305054)
			(stroke
				(width 0.1)
				(type default)
			)
			(layer "B.Fab")
		)
		(pad "1" smd circle
			(at 0.40005 0 90)
			(size 0 0)
			(layers "B.Cu" "B.Mask" "B.Paste")
			(net "PWRGD_CHB_CPU0_DIMM1")
		)
		(pad "2" smd circle
			(at -0.40005 0 90)
			(size 0 0)
			(layers "B.Cu" "B.Mask" "B.Paste")
			(net "PWRGD_FAIL_CPU0_AB")
		)
	)
	(footprint ""
		(layer "B.Cu")
		(at 164.64788 -116.296948 180)
		(property "Reference" "R1919"
			(at 0 0 0)
			(layer "B.SilkS")
			(hide yes)
			(effects
				(font
					(size 1.27 1.27)
				)
				(justify mirror)
			)
		)
		(property "Value" ""
			(at 0 0 0)
			(layer "B.Fab")
			(effects
				(font
					(size 1.27 1.27)
				)
				(justify mirror)
			)
		)
		(duplicate_pad_numbers_are_jumpers no)
		(fp_line
			(start 0.7874 0.4064)
			(end 0.7874 -0.4064)
			(stroke
				(width 0.1524)
				(type default)
			)
			(layer "B.SilkS")
		)
		(fp_line
			(start 0.7874 -0.4064)
			(end -0.7874 -0.4064)
			(stroke
				(width 0.1524)
				(type default)
			)
			(layer "B.SilkS")
		)
		(fp_line
			(start -0.7874 0.4064)
			(end 0.7874 0.4064)
			(stroke
				(width 0.1524)
				(type default)
			)
			(layer "B.SilkS")
		)
		(fp_line
			(start -0.7874 -0.4064)
			(end -0.7874 0.4064)
			(stroke
				(width 0.1524)
				(type default)
			)
			(layer "B.SilkS")
		)
		(fp_line
			(start 0.67945 0.3048)
			(end 0.67945 -0.305054)
			(stroke
				(width 0.1)
				(type default)
			)
			(layer "B.Fab")
		)
		(fp_line
			(start 0.67945 -0.305054)
			(end 0.12065 -0.305054)
			(stroke
				(width 0.1)
				(type default)
			)
			(layer "B.Fab")
		)
		(fp_line
			(start 0.12065 0.3048)
			(end 0.67945 0.3048)
			(stroke
				(width 0.1)
				(type default)
			)
			(layer "B.Fab")
		)
		(fp_line
			(start 0.12065 0.2794)
			(end 0.12065 0.3048)
			(stroke
				(width 0.1)
				(type default)
			)
			(layer "B.Fab")
		)
		(fp_line
			(start 0.12065 -0.2794)
			(end -0.12065 -0.2794)
			(stroke
				(width 0.1)
				(type default)
			)
			(layer "B.Fab")
		)
		(fp_line
			(start 0.12065 -0.305054)
			(end 0.12065 -0.2794)
			(stroke
				(width 0.1)
				(type default)
			)
			(layer "B.Fab")
		)
		(fp_line
			(start -0.120396 0.3048)
			(end -0.120396 0.2794)
			(stroke
				(width 0.1)
				(type default)
			)
			(layer "B.Fab")
		)
		(fp_line
			(start -0.120396 0.2794)
			(end 0.12065 0.2794)
			(stroke
				(width 0.1)
				(type default)
			)
			(layer "B.Fab")
		)
		(fp_line
			(start -0.12065 -0.2794)
			(end -0.12065 -0.3048)
			(stroke
				(width 0.1)
				(type default)
			)
			(layer "B.Fab")
		)
		(fp_line
			(start -0.12065 -0.3048)
			(end -0.67945 -0.3048)
			(stroke
				(width 0.1)
				(type default)
			)
			(layer "B.Fab")
		)
		(fp_line
			(start -0.67945 0.3048)
			(end -0.120396 0.3048)
			(stroke
				(width 0.1)
				(type default)
			)
			(layer "B.Fab")
		)
		(fp_line
			(start -0.67945 -0.3048)
			(end -0.67945 0.3048)
			(stroke
				(width 0.1)
				(type default)
			)
			(layer "B.Fab")
		)
		(pad "1" smd circle
			(at 0.40005 0)
			(size 0 0)
			(layers "B.Cu" "B.Mask" "B.Paste")
			(net "PWRGD_P3V3_AUX")
		)
		(pad "2" smd circle
			(at -0.40005 0)
			(size 0 0)
			(layers "B.Cu" "B.Mask" "B.Paste")
			(net "PWRGD_P3V3_AUX_PLD")
		)
	)
	(footprint ""
		(layer "B.Cu")
		(at 183.755538 -121.375424 -90)
		(property "Reference" "C1911"
			(at 0 0 90)
			(layer "B.SilkS")
			(hide yes)
			(effects
				(font
					(size 1.27 1.27)
				)
				(justify mirror)
			)
		)
		(property "Value" ""
			(at 0 0 90)
			(layer "B.Fab")
			(effects
				(font
					(size 1.27 1.27)
				)
				(justify mirror)
			)
		)
		(duplicate_pad_numbers_are_jumpers no)
		(fp_line
			(start -0.69215 0.2921)
			(end 0.69215 0.2921)
			(stroke
				(width 0.1524)
				(type default)
			)
			(layer "B.SilkS")
		)
		(fp_line
			(start 0.69215 0.2921)
			(end 0.69215 -0.2921)
			(stroke
				(width 0.1524)
				(type default)
			)
			(layer "B.SilkS")
		)
		(fp_line
			(start -0.69215 -0.2921)
			(end -0.69215 0.2921)
			(stroke
				(width 0.1524)
				(type default)
			)
			(layer "B.SilkS")
		)
		(fp_line
			(start 0.69215 -0.2921)
			(end -0.69215 -0.2921)
			(stroke
				(width 0.1524)
				(type default)
			)
			(layer "B.SilkS")
		)
		(fp_line
			(start -0.51435 0.2794)
			(end 0.51435 0.2794)
			(stroke
				(width 0.1)
				(type default)
			)
			(layer "B.Fab")
		)
		(fp_line
			(start 0.51435 0.2794)
			(end 0.51435 -0.2794)
			(stroke
				(width 0.1)
				(type default)
			)
			(layer "B.Fab")
		)
		(fp_line
			(start -0.51435 -0.2794)
			(end -0.51435 0.2794)
			(stroke
				(width 0.1)
				(type default)
			)
			(layer "B.Fab")
		)
		(fp_line
			(start 0.51435 -0.2794)
			(end -0.51435 -0.2794)
			(stroke
				(width 0.1)
				(type default)
			)
			(layer "B.Fab")
		)
		(pad "1" smd circle
			(at 0.40005 0 90)
			(size 0 0)
			(layers "B.Cu" "B.Mask" "B.Paste")
			(net "P3V3_AUX_FPGA_VCCIO1")
		)
		(pad "2" smd circle
			(at -0.40005 0 90)
			(size 0 0)
			(layers "B.Cu" "B.Mask" "B.Paste")
			(net "GND")
		)
		(zone
			(layer "B.Cu")
			(hatch none 0.5)
			(connect_pads
				(clearance 0)
			)
			(min_thickness 0.25)
			(keepout
				(tracks not_allowed)
				(vias allowed)
				(pads allowed)
				(copperpour not_allowed)
				(footprints allowed)
			)
			(placement
				(enabled no)
				(sheetname "")
			)
			(fill
				(thermal_gap 0.5)
				(thermal_bridge_width 0.5)
				(island_removal_mode 0)
			)
			(polygon
				(pts
					(xy 183.667908 -121.184924) (xy 183.609742 -121.276364) (xy 183.609742 -121.475754) (xy 183.667908 -121.565924)
					(xy 183.843168 -121.565924) (xy 183.901588 -121.475754) (xy 183.901588 -121.276364) (xy 183.843422 -121.184924)
				)
			)
		)
	)
	(footprint ""
		(layer "B.Cu")
		(at 303.554638 -194.72021 90)
		(property "Reference" "R14"
			(at 0 0 90)
			(layer "B.SilkS")
			(hide yes)
			(effects
				(font
					(size 1.27 1.27)
				)
				(justify mirror)
			)
		)
		(property "Value" ""
			(at 0 0 90)
			(layer "B.Fab")
			(effects
				(font
					(size 1.27 1.27)
				)
				(justify mirror)
			)
		)
		(duplicate_pad_numbers_are_jumpers no)
		(fp_line
			(start 0.7874 -0.4064)
			(end -0.7874 -0.4064)
			(stroke
				(width 0.1524)
				(type default)
			)
			(layer "B.SilkS")
		)
		(fp_line
			(start -0.7874 -0.4064)
			(end -0.7874 0.4064)
			(stroke
				(width 0.1524)
				(type default)
			)
			(layer "B.SilkS")
		)
		(fp_line
			(start 0.7874 0.4064)
			(end 0.7874 -0.4064)
			(stroke
				(width 0.1524)
				(type default)
			)
			(layer "B.SilkS")
		)
		(fp_line
			(start -0.7874 0.4064)
			(end 0.7874 0.4064)
			(stroke
				(width 0.1524)
				(type default)
			)
			(layer "B.SilkS")
		)
		(fp_line
			(start 0.67945 -0.305054)
			(end 0.12065 -0.305054)
			(stroke
				(width 0.1)
				(type default)
			)
			(layer "B.Fab")
		)
		(fp_line
			(start 0.12065 -0.305054)
			(end 0.12065 -0.2794)
			(stroke
				(width 0.1)
				(type default)
			)
			(layer "B.Fab")
		)
		(fp_line
			(start -0.12065 -0.3048)
			(end -0.67945 -0.3048)
			(stroke
				(width 0.1)
				(type default)
			)
			(layer "B.Fab")
		)
		(fp_line
			(start -0.67945 -0.3048)
			(end -0.67945 0.3048)
			(stroke
				(width 0.1)
				(type default)
			)
			(layer "B.Fab")
		)
		(fp_line
			(start 0.12065 -0.2794)
			(end -0.12065 -0.2794)
			(stroke
				(width 0.1)
				(type default)
			)
			(layer "B.Fab")
		)
		(fp_line
			(start -0.12065 -0.2794)
			(end -0.12065 -0.3048)
			(stroke
				(width 0.1)
				(type default)
			)
			(layer "B.Fab")
		)
		(fp_line
			(start 0.12065 0.2794)
			(end 0.12065 0.3048)
			(stroke
				(width 0.1)
				(type default)
			)
			(layer "B.Fab")
		)
		(fp_line
			(start -0.120396 0.2794)
			(end 0.12065 0.2794)
			(stroke
				(width 0.1)
				(type default)
			)
			(layer "B.Fab")
		)
		(fp_line
			(start 0.67945 0.3048)
			(end 0.67945 -0.305054)
			(stroke
				(width 0.1)
				(type default)
			)
			(layer "B.Fab")
		)
		(fp_line
			(start 0.12065 0.3048)
			(end 0.67945 0.3048)
			(stroke
				(width 0.1)
				(type default)
			)
			(layer "B.Fab")
		)
		(fp_line
			(start -0.120396 0.3048)
			(end -0.120396 0.2794)
			(stroke
				(width 0.1)
				(type default)
			)
			(layer "B.Fab")
		)
		(fp_line
			(start -0.67945 0.3048)
			(end -0.120396 0.3048)
			(stroke
				(width 0.1)
				(type default)
			)
			(layer "B.Fab")
		)
		(pad "1" smd circle
			(at 0.40005 0 270)
			(size 0 0)
			(layers "B.Cu" "B.Mask" "B.Paste")
			(net "SVID_ALERT0_CPU0_N")
		)
		(pad "2" smd circle
			(at -0.40005 0 270)
			(size 0 0)
			(layers "B.Cu" "B.Mask" "B.Paste")
			(net "SVID_ALERT0_CPU0_R_N")
		)
	)
	(footprint ""
		(layer "B.Cu")
		(at 103.979218 -241.20729 90)
		(property "Reference" "C474"
			(at 0 0 90)
			(layer "B.SilkS")
			(hide yes)
			(effects
				(font
					(size 1.27 1.27)
				)
				(justify mirror)
			)
		)
		(property "Value" ""
			(at 0 0 90)
			(layer "B.Fab")
			(effects
				(font
					(size 1.27 1.27)
				)
				(justify mirror)
			)
		)
		(duplicate_pad_numbers_are_jumpers no)
		(fp_line
			(start 1.524 -0.762)
			(end -1.524 -0.762)
			(stroke
				(width 0.1524)
				(type default)
			)
			(layer "B.SilkS")
		)
		(fp_line
			(start -1.524 -0.762)
			(end -1.524 0.762)
			(stroke
				(width 0.1524)
				(type default)
			)
			(layer "B.SilkS")
		)
		(fp_line
			(start 1.524 0.762)
			(end 1.524 -0.762)
			(stroke
				(width 0.1524)
				(type default)
			)
			(layer "B.SilkS")
		)
		(fp_line
			(start -1.524 0.762)
			(end 1.524 0.762)
			(stroke
				(width 0.1524)
				(type default)
			)
			(layer "B.SilkS")
		)
		(fp_line
			(start 1.1049 -0.724916)
			(end 1.1049 0.724916)
			(stroke
				(width 0.1)
				(type default)
			)
			(layer "B.Fab")
		)
		(fp_line
			(start -1.1049 -0.724916)
			(end 1.1049 -0.724916)
			(stroke
				(width 0.1)
				(type default)
			)
			(layer "B.Fab")
		)
		(fp_line
			(start 1.1049 0.724916)
			(end -1.1049 0.724916)
			(stroke
				(width 0.1)
				(type default)
			)
			(layer "B.Fab")
		)
		(fp_line
			(start -1.1049 0.724916)
			(end -1.1049 -0.724916)
			(stroke
				(width 0.1)
				(type default)
			)
			(layer "B.Fab")
		)
		(pad "1" smd rect
			(at 0.889 0 90)
			(size 1.016 1.27)
			(layers "B.Cu" "B.Mask" "B.Paste")
			(net "PVCCD_HV_CPU1")
		)
		(pad "2" smd rect
			(at -0.889 0 90)
			(size 1.016 1.27)
			(layers "B.Cu" "B.Mask" "B.Paste")
			(net "GND")
		)
	)
	(footprint ""
		(layer "B.Cu")
		(at 174.997618 -200.403968 -90)
		(property "Reference" "R265"
			(at 0 0 90)
			(layer "B.SilkS")
			(hide yes)
			(effects
				(font
					(size 1.27 1.27)
				)
				(justify mirror)
			)
		)
		(property "Value" ""
			(at 0 0 90)
			(layer "B.Fab")
			(effects
				(font
					(size 1.27 1.27)
				)
				(justify mirror)
			)
		)
		(duplicate_pad_numbers_are_jumpers no)
		(fp_line
			(start -0.7874 0.4064)
			(end 0.7874 0.4064)
			(stroke
				(width 0.1524)
				(type default)
			)
			(layer "B.SilkS")
		)
		(fp_line
			(start 0.7874 0.4064)
			(end 0.7874 -0.4064)
			(stroke
				(width 0.1524)
				(type default)
			)
			(layer "B.SilkS")
		)
		(fp_line
			(start -0.7874 -0.4064)
			(end -0.7874 0.4064)
			(stroke
				(width 0.1524)
				(type default)
			)
			(layer "B.SilkS")
		)
		(fp_line
			(start 0.7874 -0.4064)
			(end -0.7874 -0.4064)
			(stroke
				(width 0.1524)
				(type default)
			)
			(layer "B.SilkS")
		)
		(fp_line
			(start -0.67945 0.3048)
			(end -0.120396 0.3048)
			(stroke
				(width 0.1)
				(type default)
			)
			(layer "B.Fab")
		)
		(fp_line
			(start -0.120396 0.3048)
			(end -0.120396 0.2794)
			(stroke
				(width 0.1)
				(type default)
			)
			(layer "B.Fab")
		)
		(fp_line
			(start 0.12065 0.3048)
			(end 0.67945 0.3048)
			(stroke
				(width 0.1)
				(type default)
			)
			(layer "B.Fab")
		)
		(fp_line
			(start 0.67945 0.3048)
			(end 0.67945 -0.305054)
			(stroke
				(width 0.1)
				(type default)
			)
			(layer "B.Fab")
		)
		(fp_line
			(start -0.120396 0.2794)
			(end 0.12065 0.2794)
			(stroke
				(width 0.1)
				(type default)
			)
			(layer "B.Fab")
		)
		(fp_line
			(start 0.12065 0.2794)
			(end 0.12065 0.3048)
			(stroke
				(width 0.1)
				(type default)
			)
			(layer "B.Fab")
		)
		(fp_line
			(start -0.12065 -0.2794)
			(end -0.12065 -0.3048)
			(stroke
				(width 0.1)
				(type default)
			)
			(layer "B.Fab")
		)
		(fp_line
			(start 0.12065 -0.2794)
			(end -0.12065 -0.2794)
			(stroke
				(width 0.1)
				(type default)
			)
			(layer "B.Fab")
		)
		(fp_line
			(start -0.67945 -0.3048)
			(end -0.67945 0.3048)
			(stroke
				(width 0.1)
				(type default)
			)
			(layer "B.Fab")
		)
		(fp_line
			(start -0.12065 -0.3048)
			(end -0.67945 -0.3048)
			(stroke
				(width 0.1)
				(type default)
			)
			(layer "B.Fab")
		)
		(fp_line
			(start 0.12065 -0.305054)
			(end 0.12065 -0.2794)
			(stroke
				(width 0.1)
				(type default)
			)
			(layer "B.Fab")
		)
		(fp_line
			(start 0.67945 -0.305054)
			(end 0.12065 -0.305054)
			(stroke
				(width 0.1)
				(type default)
			)
			(layer "B.Fab")
		)
		(pad "1" smd circle
			(at 0.40005 0 90)
			(size 0 0)
			(layers "B.Cu" "B.Mask" "B.Paste")
			(net "PVNN_TERM_CPU1")
		)
		(pad "2" smd circle
			(at -0.40005 0 90)
			(size 0 0)
			(layers "B.Cu" "B.Mask" "B.Paste")
			(net "PU_CPU1_SOCKET_ID0")
		)
	)
)
